(kicad_pcb
	(version 20260206)
	(generator "pcbnew")
	(generator_version "10.0")
	(general
		(thickness 1.6)
		(legacy_teardrops no)
	)
	(paper "A4")
	(title_block
		(title "01162023_DA0F0TEBIF0_F0T_Expander_BD_F_brd_V02_OCP.brd")
		(comment 1 "Grand Teton / footprints 9508-9516 of 9728")
	)
	(layers
		(0 "F.Cu" signal "TOP")
		(4 "In1.Cu" signal "GND")
		(6 "In2.Cu" signal "VCC")
		(8 "In3.Cu" signal "VCC1")
		(10 "In4.Cu" signal "GND1")
		(12 "In5.Cu" signal "IN1")
		(14 "In6.Cu" signal "GND2")
		(16 "In7.Cu" signal "IN2")
		(18 "In8.Cu" signal "GND3")
		(20 "In9.Cu" signal "IN3")
		(22 "In10.Cu" signal "GND4")
		(24 "In11.Cu" signal "IN4")
		(26 "In12.Cu" signal "GND5")
		(28 "In13.Cu" signal "IN5")
		(30 "In14.Cu" signal "GND6")
		(32 "In15.Cu" signal "IN6")
		(34 "In16.Cu" signal "GND7")
		(2 "B.Cu" signal "BOTTOM")
		(9 "F.Adhes" user "F.Adhesive")
		(11 "B.Adhes" user "B.Adhesive")
		(13 "F.Paste" user "Package Geometry/Pastemask Top")
		(15 "B.Paste" user "Package Geometry/Pastemask Bottom")
		(5 "F.SilkS" user "Ref Des/Silkscreen Top")
		(7 "B.SilkS" user "Ref Des/Silkscreen Bottom")
		(1 "F.Mask" user "Board Geometry/Soldermask Top")
		(3 "B.Mask" user "Board Geometry/Soldermask Bottom")
		(17 "Dwgs.User" user "User.Drawings")
		(19 "Cmts.User" user "User.Comments")
		(21 "Eco1.User" user "User.Eco1")
		(23 "Eco2.User" user "User.Eco2")
		(25 "Edge.Cuts" user "Board Geometry/Outline")
		(27 "Margin" user)
		(31 "F.CrtYd" user "Package Geometry/Place Bound Top")
		(29 "B.CrtYd" user "Package Geometry/Place Bound Bottom")
		(35 "F.Fab" user "Ref Des/Assembly Top")
		(33 "B.Fab" user "Ref Des/Assembly Bottom")
	)
	(footprint ""
		(layer "B.Cu")
		(at 291.46119 -204.887068)
		(property "Reference" "R1040"
			(at 0 0 0)
			(layer "B.SilkS")
			(hide yes)
			(effects
				(font
					(size 1.27 1.27)
				)
				(justify mirror)
			)
		)
		(property "Value" ""
			(at 0 0 0)
			(layer "B.Fab")
			(effects
				(font
					(size 1.27 1.27)
				)
				(justify mirror)
			)
		)
		(duplicate_pad_numbers_are_jumpers no)
		(fp_line
			(start -0.7874 -0.4064)
			(end -0.7874 0.4064)
			(stroke
				(width 0.1524)
				(type default)
			)
			(layer "B.SilkS")
		)
		(fp_line
			(start -0.7874 0.4064)
			(end 0.7874 0.4064)
			(stroke
				(width 0.1524)
				(type default)
			)
			(layer "B.SilkS")
		)
		(fp_line
			(start 0.7874 -0.4064)
			(end -0.7874 -0.4064)
			(stroke
				(width 0.1524)
				(type default)
			)
			(layer "B.SilkS")
		)
		(fp_line
			(start 0.7874 0.4064)
			(end 0.7874 -0.4064)
			(stroke
				(width 0.1524)
				(type default)
			)
			(layer "B.SilkS")
		)
		(fp_line
			(start -0.67945 -0.3048)
			(end -0.67945 0.3048)
			(stroke
				(width 0.1)
				(type default)
			)
			(layer "B.Fab")
		)
		(fp_line
			(start -0.67945 0.3048)
			(end -0.120396 0.3048)
			(stroke
				(width 0.1)
				(type default)
			)
			(layer "B.Fab")
		)
		(fp_line
			(start -0.12065 -0.3048)
			(end -0.67945 -0.3048)
			(stroke
				(width 0.1)
				(type default)
			)
			(layer "B.Fab")
		)
		(fp_line
			(start -0.12065 -0.2794)
			(end -0.12065 -0.3048)
			(stroke
				(width 0.1)
				(type default)
			)
			(layer "B.Fab")
		)
		(fp_line
			(start -0.120396 0.2794)
			(end 0.12065 0.2794)
			(stroke
				(width 0.1)
				(type default)
			)
			(layer "B.Fab")
		)
		(fp_line
			(start -0.120396 0.3048)
			(end -0.120396 0.2794)
			(stroke
				(width 0.1)
				(type default)
			)
			(layer "B.Fab")
		)
		(fp_line
			(start 0.12065 -0.305054)
			(end 0.12065 -0.2794)
			(stroke
				(width 0.1)
				(type default)
			)
			(layer "B.Fab")
		)
		(fp_line
			(start 0.12065 -0.2794)
			(end -0.12065 -0.2794)
			(stroke
				(width 0.1)
				(type default)
			)
			(layer "B.Fab")
		)
		(fp_line
			(start 0.12065 0.2794)
			(end 0.12065 0.3048)
			(stroke
				(width 0.1)
				(type default)
			)
			(layer "B.Fab")
		)
		(fp_line
			(start 0.12065 0.3048)
			(end 0.67945 0.3048)
			(stroke
				(width 0.1)
				(type default)
			)
			(layer "B.Fab")
		)
		(fp_line
			(start 0.67945 -0.305054)
			(end 0.12065 -0.305054)
			(stroke
				(width 0.1)
				(type default)
			)
			(layer "B.Fab")
		)
		(fp_line
			(start 0.67945 0.3048)
			(end 0.67945 -0.305054)
			(stroke
				(width 0.1)
				(type default)
			)
			(layer "B.Fab")
		)
		(pad "1" smd circle
			(at 0.40005 0 180)
			(size 0 0)
			(layers "B.Cu" "B.Mask" "B.Paste")
			(net "SPI_BIC1_MISO_LS23_DIR4")
		)
		(pad "2" smd circle
			(at -0.40005 0 180)
			(size 0 0)
			(layers "B.Cu" "B.Mask" "B.Paste")
			(net "P1V8_PEX")
		)
	)
	(footprint ""
		(layer "B.Cu")
		(at 461.712564 -305.7906 -90)
		(property "Reference" "R847"
			(at 0 0 90)
			(layer "B.SilkS")
			(hide yes)
			(effects
				(font
					(size 1.27 1.27)
				)
				(justify mirror)
			)
		)
		(property "Value" ""
			(at 0 0 90)
			(layer "B.Fab")
			(effects
				(font
					(size 1.27 1.27)
				)
				(justify mirror)
			)
		)
		(duplicate_pad_numbers_are_jumpers no)
		(fp_line
			(start -0.7874 0.4064)
			(end 0.7874 0.4064)
			(stroke
				(width 0.1524)
				(type default)
			)
			(layer "B.SilkS")
		)
		(fp_line
			(start 0.7874 0.4064)
			(end 0.7874 -0.4064)
			(stroke
				(width 0.1524)
				(type default)
			)
			(layer "B.SilkS")
		)
		(fp_line
			(start -0.7874 -0.4064)
			(end -0.7874 0.4064)
			(stroke
				(width 0.1524)
				(type default)
			)
			(layer "B.SilkS")
		)
		(fp_line
			(start 0.7874 -0.4064)
			(end -0.7874 -0.4064)
			(stroke
				(width 0.1524)
				(type default)
			)
			(layer "B.SilkS")
		)
		(fp_line
			(start -0.67945 0.3048)
			(end -0.120396 0.3048)
			(stroke
				(width 0.1)
				(type default)
			)
			(layer "B.Fab")
		)
		(fp_line
			(start -0.120396 0.3048)
			(end -0.120396 0.2794)
			(stroke
				(width 0.1)
				(type default)
			)
			(layer "B.Fab")
		)
		(fp_line
			(start 0.12065 0.3048)
			(end 0.67945 0.3048)
			(stroke
				(width 0.1)
				(type default)
			)
			(layer "B.Fab")
		)
		(fp_line
			(start 0.67945 0.3048)
			(end 0.67945 -0.305054)
			(stroke
				(width 0.1)
				(type default)
			)
			(layer "B.Fab")
		)
		(fp_line
			(start -0.120396 0.2794)
			(end 0.12065 0.2794)
			(stroke
				(width 0.1)
				(type default)
			)
			(layer "B.Fab")
		)
		(fp_line
			(start 0.12065 0.2794)
			(end 0.12065 0.3048)
			(stroke
				(width 0.1)
				(type default)
			)
			(layer "B.Fab")
		)
		(fp_line
			(start -0.12065 -0.2794)
			(end -0.12065 -0.3048)
			(stroke
				(width 0.1)
				(type default)
			)
			(layer "B.Fab")
		)
		(fp_line
			(start 0.12065 -0.2794)
			(end -0.12065 -0.2794)
			(stroke
				(width 0.1)
				(type default)
			)
			(layer "B.Fab")
		)
		(fp_line
			(start -0.67945 -0.3048)
			(end -0.67945 0.3048)
			(stroke
				(width 0.1)
				(type default)
			)
			(layer "B.Fab")
		)
		(fp_line
			(start -0.12065 -0.3048)
			(end -0.67945 -0.3048)
			(stroke
				(width 0.1)
				(type default)
			)
			(layer "B.Fab")
		)
		(fp_line
			(start 0.12065 -0.305054)
			(end 0.12065 -0.2794)
			(stroke
				(width 0.1)
				(type default)
			)
			(layer "B.Fab")
		)
		(fp_line
			(start 0.67945 -0.305054)
			(end 0.12065 -0.305054)
			(stroke
				(width 0.1)
				(type default)
			)
			(layer "B.Fab")
		)
		(pad "1" smd circle
			(at 0.40005 0 90)
			(size 0 0)
			(layers "B.Cu" "B.Mask" "B.Paste")
			(net "P1V25_PEX3_VCC")
		)
		(pad "2" smd circle
			(at -0.40005 0 90)
			(size 0 0)
			(layers "B.Cu" "B.Mask" "B.Paste")
			(net "PWRGD_P1V25_PEX3")
		)
	)
	(footprint ""
		(layer "B.Cu")
		(at 170.524932 -286.399732 90)
		(property "Reference" "C3153"
			(at 0 0 90)
			(layer "B.SilkS")
			(hide yes)
			(effects
				(font
					(size 1.27 1.27)
				)
				(justify mirror)
			)
		)
		(property "Value" ""
			(at 0 0 90)
			(layer "B.Fab")
			(effects
				(font
					(size 1.27 1.27)
				)
				(justify mirror)
			)
		)
		(duplicate_pad_numbers_are_jumpers no)
		(fp_line
			(start 0.299974 -0.150114)
			(end -0.299974 -0.150114)
			(stroke
				(width 0.1)
				(type default)
			)
			(layer "B.Fab")
		)
		(fp_line
			(start -0.299974 -0.150114)
			(end -0.299974 0.150114)
			(stroke
				(width 0.1)
				(type default)
			)
			(layer "B.Fab")
		)
		(fp_line
			(start 0.299974 0.150114)
			(end 0.299974 -0.150114)
			(stroke
				(width 0.1)
				(type default)
			)
			(layer "B.Fab")
		)
		(fp_line
			(start -0.299974 0.150114)
			(end 0.299974 0.150114)
			(stroke
				(width 0.1)
				(type default)
			)
			(layer "B.Fab")
		)
		(pad "1" smd rect
			(at 0.2667 0 270)
			(size 0.3048 0.381)
			(layers "B.Cu" "B.Mask" "B.Paste")
			(net "P1V25_SERDES_VDDPLL_PEX1")
		)
		(pad "2" smd rect
			(at -0.2667 0 270)
			(size 0.3048 0.381)
			(layers "B.Cu" "B.Mask" "B.Paste")
			(net "GND")
		)
	)
	(footprint ""
		(layer "B.Cu")
		(at 287.574736 -293.99992 -90)
		(property "Reference" "C1646"
			(at 0 0 90)
			(layer "B.SilkS")
			(hide yes)
			(effects
				(font
					(size 1.27 1.27)
				)
				(justify mirror)
			)
		)
		(property "Value" ""
			(at 0 0 90)
			(layer "B.Fab")
			(effects
				(font
					(size 1.27 1.27)
				)
				(justify mirror)
			)
		)
		(duplicate_pad_numbers_are_jumpers no)
		(fp_line
			(start -0.299974 0.150114)
			(end 0.299974 0.150114)
			(stroke
				(width 0.1)
				(type default)
			)
			(layer "B.Fab")
		)
		(fp_line
			(start 0.299974 0.150114)
			(end 0.299974 -0.150114)
			(stroke
				(width 0.1)
				(type default)
			)
			(layer "B.Fab")
		)
		(fp_line
			(start -0.299974 -0.150114)
			(end -0.299974 0.150114)
			(stroke
				(width 0.1)
				(type default)
			)
			(layer "B.Fab")
		)
		(fp_line
			(start 0.299974 -0.150114)
			(end -0.299974 -0.150114)
			(stroke
				(width 0.1)
				(type default)
			)
			(layer "B.Fab")
		)
		(pad "1" smd rect
			(at 0.2667 0 90)
			(size 0.3048 0.381)
			(layers "B.Cu" "B.Mask" "B.Paste")
			(net "P0V8_PEX2")
		)
		(pad "2" smd rect
			(at -0.2667 0 90)
			(size 0.3048 0.381)
			(layers "B.Cu" "B.Mask" "B.Paste")
			(net "GND")
		)
	)
	(footprint ""
		(layer "B.Cu")
		(at 301.349918 -303.024794)
		(property "Reference" "C3342"
			(at 0 0 0)
			(layer "B.SilkS")
			(hide yes)
			(effects
				(font
					(size 1.27 1.27)
				)
				(justify mirror)
			)
		)
		(property "Value" ""
			(at 0 0 0)
			(layer "B.Fab")
			(effects
				(font
					(size 1.27 1.27)
				)
				(justify mirror)
			)
		)
		(duplicate_pad_numbers_are_jumpers no)
		(fp_line
			(start -0.299974 -0.150114)
			(end -0.299974 0.150114)
			(stroke
				(width 0.1)
				(type default)
			)
			(layer "B.Fab")
		)
		(fp_line
			(start -0.299974 0.150114)
			(end 0.299974 0.150114)
			(stroke
				(width 0.1)
				(type default)
			)
			(layer "B.Fab")
		)
		(fp_line
			(start 0.299974 -0.150114)
			(end -0.299974 -0.150114)
			(stroke
				(width 0.1)
				(type default)
			)
			(layer "B.Fab")
		)
		(fp_line
			(start 0.299974 0.150114)
			(end 0.299974 -0.150114)
			(stroke
				(width 0.1)
				(type default)
			)
			(layer "B.Fab")
		)
		(pad "1" smd rect
			(at 0.2667 0 180)
			(size 0.3048 0.381)
			(layers "B.Cu" "B.Mask" "B.Paste")
			(net "P1V8_PEX")
		)
		(pad "2" smd rect
			(at -0.2667 0 180)
			(size 0.3048 0.381)
			(layers "B.Cu" "B.Mask" "B.Paste")
			(net "GND")
		)
	)
	(footprint ""
		(layer "B.Cu")
		(at 350.65716 -316.868048)
		(property "Reference" "C4365"
			(at 0 0 0)
			(layer "B.SilkS")
			(hide yes)
			(effects
				(font
					(size 1.27 1.27)
				)
				(justify mirror)
			)
		)
		(property "Value" ""
			(at 0 0 0)
			(layer "B.Fab")
			(effects
				(font
					(size 1.27 1.27)
				)
				(justify mirror)
			)
		)
		(duplicate_pad_numbers_are_jumpers no)
		(fp_line
			(start -0.299974 -0.150114)
			(end -0.299974 0.150114)
			(stroke
				(width 0.1)
				(type default)
			)
			(layer "B.Fab")
		)
		(fp_line
			(start -0.299974 0.150114)
			(end 0.299974 0.150114)
			(stroke
				(width 0.1)
				(type default)
			)
			(layer "B.Fab")
		)
		(fp_line
			(start 0.299974 -0.150114)
			(end -0.299974 -0.150114)
			(stroke
				(width 0.1)
				(type default)
			)
			(layer "B.Fab")
		)
		(fp_line
			(start 0.299974 0.150114)
			(end 0.299974 -0.150114)
			(stroke
				(width 0.1)
				(type default)
			)
			(layer "B.Fab")
		)
		(pad "1" smd rect
			(at 0.2667 0 180)
			(size 0.3048 0.381)
			(layers "B.Cu" "B.Mask" "B.Paste")
			(net "P0V8_SERDES_VDDA_PEX3")
		)
		(pad "2" smd rect
			(at -0.2667 0 180)
			(size 0.3048 0.381)
			(layers "B.Cu" "B.Mask" "B.Paste")
			(net "GND")
		)
	)
	(footprint ""
		(layer "B.Cu")
		(at 61.549788 -290.199826 90)
		(property "Reference" "C1208"
			(at 0 0 90)
			(layer "B.SilkS")
			(hide yes)
			(effects
				(font
					(size 1.27 1.27)
				)
				(justify mirror)
			)
		)
		(property "Value" ""
			(at 0 0 90)
			(layer "B.Fab")
			(effects
				(font
					(size 1.27 1.27)
				)
				(justify mirror)
			)
		)
		(duplicate_pad_numbers_are_jumpers no)
		(fp_line
			(start 0.299974 -0.150114)
			(end -0.299974 -0.150114)
			(stroke
				(width 0.1)
				(type default)
			)
			(layer "B.Fab")
		)
		(fp_line
			(start -0.299974 -0.150114)
			(end -0.299974 0.150114)
			(stroke
				(width 0.1)
				(type default)
			)
			(layer "B.Fab")
		)
		(fp_line
			(start 0.299974 0.150114)
			(end 0.299974 -0.150114)
			(stroke
				(width 0.1)
				(type default)
			)
			(layer "B.Fab")
		)
		(fp_line
			(start -0.299974 0.150114)
			(end 0.299974 0.150114)
			(stroke
				(width 0.1)
				(type default)
			)
			(layer "B.Fab")
		)
		(pad "1" smd rect
			(at 0.2667 0 270)
			(size 0.3048 0.381)
			(layers "B.Cu" "B.Mask" "B.Paste")
			(net "P0V8_SERDES_VDDA_PEX0")
		)
		(pad "2" smd rect
			(at -0.2667 0 270)
			(size 0.3048 0.381)
			(layers "B.Cu" "B.Mask" "B.Paste")
			(net "GND")
		)
	)
	(footprint ""
		(layer "B.Cu")
		(at 279.974802 -290.941506 90)
		(property "Reference" "C3408"
			(at 0 0 90)
			(layer "B.SilkS")
			(hide yes)
			(effects
				(font
					(size 1.27 1.27)
				)
				(justify mirror)
			)
		)
		(property "Value" ""
			(at 0 0 90)
			(layer "B.Fab")
			(effects
				(font
					(size 1.27 1.27)
				)
				(justify mirror)
			)
		)
		(duplicate_pad_numbers_are_jumpers no)
		(fp_line
			(start 0.299974 -0.150114)
			(end -0.299974 -0.150114)
			(stroke
				(width 0.1)
				(type default)
			)
			(layer "B.Fab")
		)
		(fp_line
			(start -0.299974 -0.150114)
			(end -0.299974 0.150114)
			(stroke
				(width 0.1)
				(type default)
			)
			(layer "B.Fab")
		)
		(fp_line
			(start 0.299974 0.150114)
			(end 0.299974 -0.150114)
			(stroke
				(width 0.1)
				(type default)
			)
			(layer "B.Fab")
		)
		(fp_line
			(start -0.299974 0.150114)
			(end 0.299974 0.150114)
			(stroke
				(width 0.1)
				(type default)
			)
			(layer "B.Fab")
		)
		(pad "1" smd rect
			(at 0.2667 0 270)
			(size 0.3048 0.381)
			(layers "B.Cu" "B.Mask" "B.Paste")
			(net "PCEPLL7_VDDA18_PEX2")
		)
		(pad "2" smd rect
			(at -0.2667 0 270)
			(size 0.3048 0.381)
			(layers "B.Cu" "B.Mask" "B.Paste")
			(net "GND")
		)
	)
	(footprint ""
		(layer "B.Cu")
		(at 366.316768 -324.163944 -90)
		(property "Reference" "C4371"
			(at 0 0 90)
			(layer "B.SilkS")
			(hide yes)
			(effects
				(font
					(size 1.27 1.27)
				)
				(justify mirror)
			)
		)
		(property "Value" ""
			(at 0 0 90)
			(layer "B.Fab")
			(effects
				(font
					(size 1.27 1.27)
				)
				(justify mirror)
			)
		)
		(duplicate_pad_numbers_are_jumpers no)
		(fp_line
			(start -1.2954 0.5842)
			(end 1.2954 0.5842)
			(stroke
				(width 0.1524)
				(type default)
			)
			(layer "B.SilkS")
		)
		(fp_line
			(start 1.2954 0.5842)
			(end 1.2954 -0.5842)
			(stroke
				(width 0.1524)
				(type default)
			)
			(layer "B.SilkS")
		)
		(fp_line
			(start -1.2954 -0.5842)
			(end -1.2954 0.5842)
			(stroke
				(width 0.1524)
				(type default)
			)
			(layer "B.SilkS")
		)
		(fp_line
			(start 1.2954 -0.5842)
			(end -1.2954 -0.5842)
			(stroke
				(width 0.1524)
				(type default)
			)
			(layer "B.SilkS")
		)
		(fp_line
			(start -0.8636 0.4572)
			(end 0.8636 0.4572)
			(stroke
				(width 0.1)
				(type default)
			)
			(layer "B.Fab")
		)
		(fp_line
			(start 0.8636 0.4572)
			(end 0.8636 0.4064)
			(stroke
				(width 0.1)
				(type default)
			)
			(layer "B.Fab")
		)
		(fp_line
			(start -1.1938 0.4064)
			(end -0.8636 0.4064)
			(stroke
				(width 0.1)
				(type default)
			)
			(layer "B.Fab")
		)
		(fp_line
			(start -0.8636 0.4064)
			(end -0.8636 0.4572)
			(stroke
				(width 0.1)
				(type default)
			)
			(layer "B.Fab")
		)
		(fp_line
			(start 0.8636 0.4064)
			(end 1.1938 0.4064)
			(stroke
				(width 0.1)
				(type default)
			)
			(layer "B.Fab")
		)
		(fp_line
			(start 1.1938 0.4064)
			(end 1.1938 -0.4064)
			(stroke
				(width 0.1)
				(type default)
			)
			(layer "B.Fab")
		)
		(fp_line
			(start -1.1938 -0.4064)
			(end -1.1938 0.4064)
			(stroke
				(width 0.1)
				(type default)
			)
			(layer "B.Fab")
		)
		(fp_line
			(start -0.8636 -0.4064)
			(end -1.1938 -0.4064)
			(stroke
				(width 0.1)
				(type default)
			)
			(layer "B.Fab")
		)
		(fp_line
			(start 0.8636 -0.4064)
			(end 0.8636 -0.4572)
			(stroke
				(width 0.1)
				(type default)
			)
			(layer "B.Fab")
		)
		(fp_line
			(start 1.1938 -0.4064)
			(end 0.8636 -0.4064)
			(stroke
				(width 0.1)
				(type default)
			)
			(layer "B.Fab")
		)
		(fp_line
			(start -0.8636 -0.4572)
			(end -0.8636 -0.4064)
			(stroke
				(width 0.1)
				(type default)
			)
			(layer "B.Fab")
		)
		(fp_line
			(start 0.8636 -0.4572)
			(end -0.8636 -0.4572)
			(stroke
				(width 0.1)
				(type default)
			)
			(layer "B.Fab")
		)
		(pad "1" smd rect
			(at 0.7366 0 180)
			(size 0.7112 0.8128)
			(layers "B.Cu" "B.Mask" "B.Paste")
			(net "P0V8_SERDES_VDDA_PEX3_C5")
		)
		(pad "2" smd rect
			(at -0.7366 0 180)
			(size 0.7112 0.8128)
			(layers "B.Cu" "B.Mask" "B.Paste")
			(net "GND")
		)
	)
)
